G04 ================== begin FILE IDENTIFICATION RECORD ==================*
G04 Layout Name:  E:/<user>/9332_F0TG_MB_C/brd/0417/9332_F0TG_MB_C_V02_0417_0820.brd*
G04 Film Name:    outline*
G04 File Format:  Gerber RS274X*
G04 File Origin:  Cadence Allegro 17.2-S081*
G04 Origin Date:  Wed Apr 19 14:50:16 2023*
G04 *
G04 Layer:  BOARD GEOMETRY/DESIGN_OUTLINE*
G04 Layer:  BOARD GEOMETRY/CUTOUT*
G04 *
G04 Offset:    (0.00 0.00)*
G04 Mirror:    No*
G04 Mode:      Positive*
G04 Rotation:  0*
G04 FullContactRelief:  No*
G04 UndefLineWidth:     6.00*
G04 ================== end FILE IDENTIFICATION RECORD ====================*
%FSLAX25Y25*MOIN*%
%IR0*IPPOS*OFA0.00000B0.00000*MIA0B0*SFA1.00000B1.00000*%
%ADD10C,.006*%
G75*
%LPD*%
G75*
G54D10*
G01X2306Y311361D02*
G03X0Y305794I5567J-5567D01*
G01Y54252D01*
G03X7874Y46378I7874J0D01*
G01X43709D01*
G02X51583Y38504I0J-7874D01*
G01Y1969D01*
G03X53551Y0I1968J0D01*
G01X319693D01*
G03X321661Y1969I0J1969D01*
G01Y38504D01*
G02X329535Y46378I7874J0D01*
G01X488591D01*
G02X496465Y38504I0J-7874D01*
G01Y22756D01*
G03X498433Y20787I1968J-1D01*
G01X764575D01*
G03X766543Y22756I-1J1969D01*
G01Y38504D01*
G02X774417Y46378I7874J0D01*
G01X871260D01*
G03X879134Y54252I0J7874D01*
G01Y134331D01*
G02X887008Y142205I7874J0D01*
G01X1011024D01*
G02X1018898Y134331I0J-7874D01*
G01Y54252D01*
G03X1026772Y46378I7874J0D01*
G01X1518118D01*
G02X1525992Y38504I0J-7874D01*
G01Y1969D01*
G03X1527961Y0I1969J0D01*
G01X1794102D01*
G03X1796071Y1969I0J1969D01*
G01Y38504D01*
G02X1803945Y46378I7874J0D01*
G01X1849606D01*
G03X1857480Y54252I0J7874D01*
G01Y305794D01*
G03X1855174Y311361I-7873J0D01*
G01X1846007Y320528D01*
G02X1843701Y326096I5568J5568D01*
G01Y1593983D01*
G03X1841395Y1599550I-7873J0D01*
G01X1834196Y1606749D01*
G02X1831890Y1612317I5568J5568D01*
G01Y1732244D01*
G03X1824016Y1740118I-7874J0D01*
G01X1091791D01*
G03X1089823Y1738150I0J-1968D01*
G01Y1736890D01*
G02X1087854Y1734921I-1969J0D01*
G01X769705D01*
G02X767736Y1736890I0J1969D01*
G01Y1738150D01*
G03X765768Y1740118I-1968J0D01*
G01X33465D01*
G03X25591Y1732244I0J-7874D01*
G01Y1612317D01*
G02X23284Y1606749I-7875J1D01*
G01X10180Y1593645D01*
G03X7874Y1588077I5568J-5568D01*
G01Y320191D01*
G02X5568Y314623I-7874J0D01*
G01X2306Y311361D01*
G01X38583Y87795D02*
G02X16535I-11024J0D01*
G02X38583I11024J0D01*
G01X34390Y1533228D02*
G02X19705I-7342J0D01*
G02X34390I7343J0D01*
G01X51732Y631890D02*
G02X29685I-11024J0D01*
G02X51732I11023J0D01*
G01Y1368898D02*
G02X29685I-11024J0D01*
G02X51732I11023J0D01*
G01X52141Y119148D02*
X56741Y123451D01*
G02X65079Y114538I4169J-4456D01*
G01X60479Y110235D01*
G02X52141Y119148I-4169J4456D01*
G01X40157Y1714961D02*
G02X62205I11024J0D01*
G02X40157I-11024J0D01*
G01X86933Y1369350D02*
G02X72248I-7343J0D01*
G02X86933I7342J0D01*
G01X137618Y605378D02*
G02X98248I-19685J0D01*
G02X137618I19685J0D01*
G01X146929Y1482244D02*
G02X129213I-8858J0D01*
G02X146929I8858J0D01*
G01X144626Y1533228D02*
G02X129941I-7343J0D01*
G02X144626I7342J0D01*
G01X172520Y1593661D02*
G02X154803I-8858J0D01*
G02X172520I8859J0D01*
G01X157728Y294335D02*
G02X197098I19685J0D01*
G01Y260083D01*
G02X157728I-19685J0D01*
G01Y294335D01*
G01X222760Y658012D02*
G02X208075I-7342J0D01*
G02X222760I7343J0D01*
G01X247177Y191535D02*
X253476D01*
G02Y178937I0J-6299D01*
G01X247177D01*
G02Y191535I0J6299D01*
G01X284579Y185236D02*
G02X269618I-7481J0D01*
G02X284579I7481J0D01*
G01X282795Y1019252D02*
G02X267047I-7874J0D01*
G02X282795I7874J0D01*
G01X283783Y1357539D02*
G02X269098I-7342J0D01*
G02X283783I7343J0D01*
G01X328071Y838543D02*
G02X312323I-7874J0D01*
G02X328071I7874J0D01*
G01Y1199961D02*
G02X312323I-7874J0D01*
G02X328071I7874J0D01*
G01X384646Y87795D02*
G02X362598I-11024J0D01*
G02X384646I11024J0D01*
G01X365287Y191535D02*
X371587D01*
G02Y178937I0J-6299D01*
G01X365287D01*
G02Y191535I0J6299D01*
G01X402689Y185236D02*
G02X387728I-7480J0D01*
G02X402689I7481J0D01*
G01X406694Y1714961D02*
G02X384647I-11023J0D01*
G02X406694I11023J0D01*
G01X427484Y655965D02*
G02X412799I-7343J0D01*
G02X427484I7343J0D01*
G01X451106Y1339823D02*
G02X436421I-7343J0D01*
G02X451106I7343J0D01*
G01X434793Y1698268D02*
G02X447293I6250J0D01*
G02X434793I-6250J0D01*
G01X530516Y578130D02*
G02X515831I-7343J0D01*
G02X530516I7342J0D01*
G01X569016Y838543D02*
G02X553268I-7874J0D01*
G02X569016I7874J0D01*
G01Y1199961D02*
G02X553268I-7874J0D01*
G02X569016I7874J0D01*
G01X614291Y1019252D02*
G02X598543I-7874J0D01*
G02X614291I7874J0D01*
G01X672047Y631890D02*
G02X650000I-11024J0D01*
G02X672047I11023J0D01*
G01X688783Y1385138D02*
G02X674098I-7343J0D01*
G02X688783I7343J0D01*
G01X682087Y1593661D02*
G02X664370I-8859J0D01*
G02X682087I8859J0D01*
G01X684500Y294362D02*
G02X723870I19685J0D01*
G01Y260110D01*
G02X684500I-19685J0D01*
G01Y294362D01*
G01X707677Y1482244D02*
G02X689961I-8858J0D01*
G02X707677I8858J0D01*
G01X718701Y1714961D02*
G02X696654I-11024J0D01*
G02X718701I11023J0D01*
G01X783287Y605413D02*
G02X743917I-19685J0D01*
G02X783287I19685J0D01*
G01X811811Y87795D02*
G02X789764I-11023J0D01*
G02X811811I11023J0D01*
G01X816535Y204724D02*
G02X794882I-10826J0D01*
G02X816535I10827J0D01*
G01X799020Y1385138D02*
G02X784335I-7343J0D01*
G02X799020I7342J0D01*
G01X849114Y1420331D02*
G02X833366I-7874J0D01*
G02X849114I7874J0D01*
G01X880965Y1145276D02*
G02X866280I-7342J0D01*
G02X880965I7343J0D01*
G01X895789Y1528196D02*
G02X879254I-8267J0D01*
G02X895789I8268J0D01*
G01X904134Y175177D02*
G02X896260I-3937J0D01*
G02X904134I3937J0D01*
G01X936673Y311614D02*
X920807D01*
G02X936673I7933J10039D01*
G01X942717Y757874D02*
G02X920669I-11024J0D01*
G02X942717I11024J0D01*
G01Y1072835D02*
G02X920669I-11024J0D01*
G02X942717I11024J0D01*
G01Y1387795D02*
G02X920669I-11024J0D01*
G02X942717I11024J0D01*
G01X948622Y155197D02*
G02X940748I-3937J0D01*
G02X948622I3937J0D01*
G01X991201Y1145276D02*
G02X976516I-7343J0D01*
G02X991201I7343J0D01*
G01X1024114Y1420331D02*
G02X1008366I-7874J0D01*
G02X1024114I7874J0D01*
G01X1056890Y87795D02*
G02X1034843I-11023J0D01*
G02X1056890I11024J0D01*
G01X1068504Y204724D02*
G02X1046850I-10827J0D01*
G02X1068504I10827J0D01*
G01X1060303Y1369350D02*
G02X1045618I-7343J0D01*
G02X1060303I7343J0D01*
G01X1113760Y605378D02*
G02X1074390I-19685J0D01*
G02X1113760I19685J0D01*
G01X1133870Y294335D02*
G02X1173240I19685J0D01*
G01Y260083D01*
G02X1133870I-19685J0D01*
G01Y294335D01*
G01X1154803Y1515236D02*
G02X1137087I-8858J0D01*
G02X1154803I8858J0D01*
G01X1166732Y1714961D02*
G02X1144685I-11024J0D01*
G02X1166732I11023J0D01*
G01X1180394Y1626654D02*
G02X1162677I-8859J0D01*
G02X1180394I8859J0D01*
G01X1258937Y1019252D02*
G02X1243189I-7874J0D01*
G02X1258937I7874J0D01*
G01X1257154Y1357539D02*
G02X1242469I-7343J0D01*
G02X1257154I7343J0D01*
G01X1282283Y631890D02*
G02X1260236I-11023J0D01*
G02X1282283I11023J0D01*
G01X1304213Y838543D02*
G02X1288465I-7874J0D01*
G02X1304213I7874J0D01*
G01Y1199961D02*
G02X1288465I-7874J0D01*
G02X1304213I7874J0D01*
G01X1377626Y582303D02*
G02X1362941I-7343J0D01*
G02X1377626I7342J0D01*
G01X1424476Y1339823D02*
G02X1409791I-7343J0D01*
G02X1424476I7342J0D01*
G01X1410187Y1698268D02*
G02X1422687I6250J0D01*
G02X1410187I-6250J0D01*
G01X1472829Y1714961D02*
G02X1450782I-11024J0D01*
G02X1472829I11023J0D01*
G01X1510630Y87795D02*
G02X1488583I-11023J0D01*
G02X1510630I11024J0D01*
G01X1540894Y682343D02*
G02X1526209I-7343J0D01*
G02X1540894I7342J0D01*
G01X1545157Y838543D02*
G02X1529409I-7874J0D01*
G02X1545157I7874J0D01*
G01Y1199961D02*
G02X1529409I-7874J0D01*
G02X1545157I7874J0D01*
G01X1590433Y1019252D02*
G02X1574685I-7874J0D01*
G02X1590433I7874J0D01*
G01X1637075Y1383524D02*
G02X1622390I-7343J0D01*
G02X1637075I7343J0D01*
G01X1660642Y294362D02*
G02X1700012I19685J0D01*
G01Y260110D01*
G02X1660642I-19685J0D01*
G01Y294362D01*
G01X1672232Y642972D02*
G02X1657547I-7343J0D01*
G02X1672232I7342J0D01*
G01X1689961Y1626654D02*
G02X1672244I-8859J0D01*
G02X1689961I8859J0D01*
G01X1715551Y1515236D02*
G02X1697835I-8858J0D01*
G02X1715551I8858J0D01*
G01X1759429Y605413D02*
G02X1720059I-19685J0D01*
G02X1759429I19685J0D01*
G01X1721673Y1570984D02*
G02X1706988I-7342J0D01*
G02X1721673I7343J0D01*
G01X1747311Y1383524D02*
G02X1732626I-7343J0D01*
G02X1747311I7343J0D01*
G01X1768917Y159134D02*
G02X1754232I-7342J0D01*
G02X1768917I7343J0D01*
G01X1773031Y1714961D02*
G02X1760827I-6102J0D01*
G02X1773031I6102J0D01*
G01X1817323D02*
G02X1795276I-11023J0D01*
G02X1817323I11024J0D01*
G01X1827795Y631890D02*
G02X1805748I-11023J0D01*
G02X1827795I11024J0D01*
G01Y1368898D02*
G02X1805748I-11023J0D01*
G02X1827795I11024J0D01*
G01X1840945Y87795D02*
G02X1818898I-11023J0D01*
G02X1840945I11023J0D01*
G01X1823819Y133465D02*
G02X1836024I6103J0D01*
G01Y127165D01*
G02X1823819I-6103J0D01*
G01Y133465D01*
G01X1831909Y1570984D02*
G02X1817224I-7342J0D01*
G02X1831909I7343J0D01*
G01X1845492Y201929D02*
G02X1830807I-7342J0D01*
G02X1845492I7343J0D01*
M02*
